# T6G (Grand Teton) — schematic netlist excerpt (pin names and nets, part order shuffled) for the footprints in the layout excerpt that follows; sources: Cadence DE-HDL packaged netlist, KiCad conversion of 04192023_DAF0TMB3IC0_F0TG_MB_C_brd_V02_OCP.brd

C934  Q_CAP_DIFFBUS  DIFF BUS_0.22UF 6.3V 20% X6S  pkg C0201  page 63 : \1\ = P5E_CPU0_P1_TX_C_DN<15> ; \2\ = P5E_CPU0_P1_TX_DN<15>

JP6500  CONN3_210HP1030BR1  CONN3_210-HP1-030BR1 IO  pkg HEADER1X3XG  page 184
  \1\  = SMB_MUX_RT_R2_SCL
  \2\  = SMB_MUX_RT_R2_SDA
  \3\  = GND

R6294  Q_RES  10K 1% CHIP  pkg 0402LF  page 179 : A = P3V3_AUX ; B = USB_HUB2_MRP_I2C_SLV_CFG0

(kicad_pcb
	(version 20260206)
	(generator "pcbnew")
	(generator_version "10.0")
	(general
		(thickness 1.6)
		(legacy_teardrops no)
	)
	(paper "A4")
	(title_block
		(title "04192023_DAF0TMB3IC0_F0TG_MB_C_brd_V02_OCP.brd")
		(comment 1 "Grand Teton / footprints 1386-1388 of 8354")
	)
	(layers
		(0 "F.Cu" signal "TOP")
		(4 "In1.Cu" signal "GND")
		(6 "In2.Cu" signal "IN1")
		(8 "In3.Cu" signal "GND1")
		(10 "In4.Cu" signal "IN2")
		(12 "In5.Cu" signal "GND2")
		(14 "In6.Cu" signal "IN3")
		(16 "In7.Cu" signal "GND3")
		(18 "In8.Cu" signal "VCC")
		(20 "In9.Cu" signal "VCC1")
		(22 "In10.Cu" signal "GND4")
		(24 "In11.Cu" signal "IN4")
		(26 "In12.Cu" signal "GND5")
		(28 "In13.Cu" signal "IN5")
		(30 "In14.Cu" signal "GND6")
		(32 "In15.Cu" signal "IN6")
		(34 "In16.Cu" signal "GND7")
		(2 "B.Cu" signal "BOTTOM")
		(9 "F.Adhes" user "F.Adhesive")
		(11 "B.Adhes" user "B.Adhesive")
		(13 "F.Paste" user "Package Geometry/Pastemask Top")
		(15 "B.Paste" user "Package Geometry/Pastemask Bottom")
		(5 "F.SilkS" user "Ref Des/Silkscreen Top")
		(7 "B.SilkS" user "Ref Des/Silkscreen Bottom")
		(1 "F.Mask" user "Board Geometry/Soldermask Top")
		(3 "B.Mask" user "Board Geometry/Soldermask Bottom")
		(17 "Dwgs.User" user "User.Drawings")
		(19 "Cmts.User" user "User.Comments")
		(21 "Eco1.User" user "User.Eco1")
		(23 "Eco2.User" user "User.Eco2")
		(25 "Edge.Cuts" user "Board Geometry/Outline")
		(27 "Margin" user)
		(31 "F.CrtYd" user "Package Geometry/Place Bound Top")
		(29 "B.CrtYd" user "Package Geometry/Place Bound Bottom")
		(35 "F.Fab" user "Ref Des/Assembly Top")
		(33 "B.Fab" user "Ref Des/Assembly Bottom")
	)
	(footprint ""
		(layer "F.Cu")
		(at 111.251238 -41.17975 -90)
		(property "Reference" "R6294"
			(at 0 0 270)
			(layer "F.SilkS")
			(hide yes)
			(effects
				(font
					(size 1.27 1.27)
				)
			)
		)
		(property "Value" ""
			(at 0 0 270)
			(layer "F.Fab")
			(effects
				(font
					(size 1.27 1.27)
				)
			)
		)
		(duplicate_pad_numbers_are_jumpers no)
		(fp_line
			(start -0.7874 0.4064)
			(end -0.7874 -0.4064)
			(stroke
				(width 0.1524)
				(type default)
			)
			(layer "F.SilkS")
		)
		(fp_line
			(start 0.7874 0.4064)
			(end -0.7874 0.4064)
			(stroke
				(width 0.1524)
				(type default)
			)
			(layer "F.SilkS")
		)
		(fp_line
			(start -0.7874 -0.4064)
			(end 0.7874 -0.4064)
			(stroke
				(width 0.1524)
				(type default)
			)
			(layer "F.SilkS")
		)
		(fp_line
			(start 0.7874 -0.4064)
			(end 0.7874 0.4064)
			(stroke
				(width 0.1524)
				(type default)
			)
			(layer "F.SilkS")
		)
		(fp_line
			(start -0.67945 0.3048)
			(end -0.67945 -0.305054)
			(stroke
				(width 0.1)
				(type default)
			)
			(layer "F.Fab")
		)
		(fp_line
			(start -0.12065 0.3048)
			(end -0.67945 0.3048)
			(stroke
				(width 0.1)
				(type default)
			)
			(layer "F.Fab")
		)
		(fp_line
			(start 0.120396 0.3048)
			(end 0.120396 0.2794)
			(stroke
				(width 0.1)
				(type default)
			)
			(layer "F.Fab")
		)
		(fp_line
			(start 0.67945 0.3048)
			(end 0.120396 0.3048)
			(stroke
				(width 0.1)
				(type default)
			)
			(layer "F.Fab")
		)
		(fp_line
			(start -0.12065 0.2794)
			(end -0.12065 0.3048)
			(stroke
				(width 0.1)
				(type default)
			)
			(layer "F.Fab")
		)
		(fp_line
			(start 0.120396 0.2794)
			(end -0.12065 0.2794)
			(stroke
				(width 0.1)
				(type default)
			)
			(layer "F.Fab")
		)
		(fp_line
			(start -0.12065 -0.2794)
			(end 0.12065 -0.2794)
			(stroke
				(width 0.1)
				(type default)
			)
			(layer "F.Fab")
		)
		(fp_line
			(start 0.12065 -0.2794)
			(end 0.12065 -0.3048)
			(stroke
				(width 0.1)
				(type default)
			)
			(layer "F.Fab")
		)
		(fp_line
			(start 0.12065 -0.3048)
			(end 0.67945 -0.3048)
			(stroke
				(width 0.1)
				(type default)
			)
			(layer "F.Fab")
		)
		(fp_line
			(start 0.67945 -0.3048)
			(end 0.67945 0.3048)
			(stroke
				(width 0.1)
				(type default)
			)
			(layer "F.Fab")
		)
		(fp_line
			(start -0.67945 -0.305054)
			(end -0.12065 -0.305054)
			(stroke
				(width 0.1)
				(type default)
			)
			(layer "F.Fab")
		)
		(fp_line
			(start -0.12065 -0.305054)
			(end -0.12065 -0.2794)
			(stroke
				(width 0.1)
				(type default)
			)
			(layer "F.Fab")
		)
		(pad "1" smd circle
			(at -0.40005 0 270)
			(size 0 0)
			(layers "F.Cu" "F.Mask" "F.Paste")
			(net "P3V3_AUX")
		)
		(pad "2" smd circle
			(at 0.40005 0 270)
			(size 0 0)
			(layers "F.Cu" "F.Mask" "F.Paste")
			(net "USB_HUB2_MRP_I2C_SLV_CFG0")
		)
	)
	(footprint ""
		(layer "F.Cu")
		(at 272.507202 -363.010704)
		(property "Reference" "JP6500"
			(at -1.4097 -2.009648 0)
			(unlocked yes)
			(layer "F.SilkS")
			(effects
				(font
					(size 0.7874 0.5842)
					(thickness 0.1524)
				)
				(justify left)
			)
		)
		(property "Value" ""
			(at 0 0 0)
			(layer "F.Fab")
			(effects
				(font
					(size 1.27 1.27)
				)
			)
		)
		(duplicate_pad_numbers_are_jumpers no)
		(fp_line
			(start -1.249934 -1.320038)
			(end 1.249934 -1.320038)
			(stroke
				(width 0.1524)
				(type default)
			)
			(layer "F.SilkS")
		)
		(fp_line
			(start -1.249934 6.400038)
			(end -1.249934 -1.320038)
			(stroke
				(width 0.1524)
				(type default)
			)
			(layer "F.SilkS")
		)
		(fp_line
			(start 1.249934 -1.320038)
			(end 1.249934 6.400038)
			(stroke
				(width 0.1524)
				(type default)
			)
			(layer "F.SilkS")
		)
		(fp_line
			(start 1.249934 6.400038)
			(end -1.249934 6.400038)
			(stroke
				(width 0.1524)
				(type default)
			)
			(layer "F.SilkS")
		)
		(fp_poly
			(pts
				(xy -2.5654 -0.556514) (xy -1.452372 0) (xy -2.5654 0.556514)
			)
			(stroke
				(width 0)
				(type default)
			)
			(fill yes)
			(layer "F.SilkS")
		)
		(fp_line
			(start -1.249934 -1.320038)
			(end 1.249934 -1.320038)
			(stroke
				(width 0.1)
				(type default)
			)
			(layer "F.Fab")
		)
		(fp_line
			(start -1.249934 6.400038)
			(end -1.249934 -1.320038)
			(stroke
				(width 0.1)
				(type default)
			)
			(layer "F.Fab")
		)
		(fp_line
			(start 1.249934 -1.320038)
			(end 1.249934 6.400038)
			(stroke
				(width 0.1)
				(type default)
			)
			(layer "F.Fab")
		)
		(fp_line
			(start 1.249934 6.400038)
			(end -1.249934 6.400038)
			(stroke
				(width 0.1)
				(type default)
			)
			(layer "F.Fab")
		)
		(fp_poly
			(pts
				(xy -2.5654 -0.556514) (xy -1.452372 0) (xy -2.5654 0.556514)
			)
			(stroke
				(width 0)
				(type default)
			)
			(fill yes)
			(layer "F.Fab")
		)
		(fp_text user "3"
			(at -1.778 5.13207 0)
			(unlocked yes)
			(layer "F.SilkS")
			(effects
				(font
					(size 0.7874 0.5842)
					(thickness 0.1524)
				)
			)
		)
		(fp_text user "3"
			(at -1.1557 5.18287 0)
			(unlocked yes)
			(layer "B.SilkS")
			(effects
				(font
					(size 0.7874 0.5842)
					(thickness 0.1524)
				)
				(justify mirror)
			)
		)
		(fp_text user "1"
			(at -1.143 0.02667 0)
			(unlocked yes)
			(layer "B.SilkS")
			(effects
				(font
					(size 0.7874 0.5842)
					(thickness 0.1524)
				)
				(justify mirror)
			)
		)
		(fp_text user "3"
			(at -1.1557 5.18287 0)
			(unlocked yes)
			(layer "B.Fab")
			(effects
				(font
					(size 0.7874 0.5842)
					(thickness 0.1524)
				)
				(justify mirror)
			)
		)
		(fp_text user "1"
			(at -1.143 0.02667 0)
			(unlocked yes)
			(layer "B.Fab")
			(effects
				(font
					(size 0.7874 0.5842)
					(thickness 0.1524)
				)
				(justify mirror)
			)
		)
		(fp_text user "3"
			(at -1.778 5.13207 0)
			(unlocked yes)
			(layer "F.Fab")
			(effects
				(font
					(size 0.7874 0.5842)
					(thickness 0.1524)
				)
			)
		)
		(pad "1" thru_hole rect
			(at 0 0)
			(size 1.5494 1.5494)
			(drill 1.0414)
			(layers "*.Cu" "*.Mask")
			(remove_unused_layers no)
			(net "SMB_MUX_RT_R2_SCL")
			(clearance 0)
			(padstack
				(mode front_inner_back)
				(layer "Inner"
					(shape circle)
					(size 1.5494 1.5494)
					(clearance 0)
				)
				(layer "B.Cu"
					(shape rect)
					(size 1.5494 1.5494)
					(clearance 0)
				)
			)
		)
		(pad "2" thru_hole circle
			(at 0 2.54)
			(size 1.5494 1.5494)
			(drill 1.0414)
			(layers "*.Cu" "*.Mask")
			(remove_unused_layers no)
			(net "SMB_MUX_RT_R2_SDA")
			(clearance 0)
		)
		(pad "3" thru_hole circle
			(at 0 5.08)
			(size 1.5494 1.5494)
			(drill 1.0414)
			(layers "*.Cu" "*.Mask")
			(remove_unused_layers no)
			(net "GND")
			(clearance 0)
		)
	)
	(footprint ""
		(layer "F.Cu")
		(at 358.268524 -388.767828)
		(property "Reference" "C934"
			(at 0 0 0)
			(layer "F.SilkS")
			(hide yes)
			(effects
				(font
					(size 1.27 1.27)
				)
			)
		)
		(property "Value" ""
			(at 0 0 0)
			(layer "F.Fab")
			(effects
				(font
					(size 1.27 1.27)
				)
			)
		)
		(duplicate_pad_numbers_are_jumpers no)
		(fp_line
			(start -0.299974 -0.150114)
			(end 0.299974 -0.150114)
			(stroke
				(width 0.1)
				(type default)
			)
			(layer "F.Fab")
		)
		(fp_line
			(start -0.299974 0.150114)
			(end -0.299974 -0.150114)
			(stroke
				(width 0.1)
				(type default)
			)
			(layer "F.Fab")
		)
		(fp_line
			(start 0.299974 -0.150114)
			(end 0.299974 0.150114)
			(stroke
				(width 0.1)
				(type default)
			)
			(layer "F.Fab")
		)
		(fp_line
			(start 0.299974 0.150114)
			(end -0.299974 0.150114)
			(stroke
				(width 0.1)
				(type default)
			)
			(layer "F.Fab")
		)
		(pad "1" smd rect
			(at -0.2667 0)
			(size 0.3048 0.381)
			(layers "F.Cu" "F.Mask" "F.Paste")
			(net "P5E_CPU0_P1_TX_C_DN<15>")
		)
		(pad "2" smd rect
			(at 0.2667 0)
			(size 0.3048 0.381)
			(layers "F.Cu" "F.Mask" "F.Paste")
			(net "P5E_CPU0_P1_TX_DN<15>")
		)
	)
)
